# TIMECARD (Time Appliance Project (Time Card)) — schematic netlist excerpt (pin names and nets, part order shuffled) for the footprints in the layout excerpt that follows; sources: Cadence DE-HDL packaged netlist, KiCad conversion of R4006-B0001-02_R01.brd

C202  CAPACITOR  0.1UF 10V 10%  pkg SMC_0402R_H022  page 14 : \1\ = XP3R3V_FPGA ; \2\ = SG
R26  RESISTOR  33OHM 1%  pkg SMC_0402R_H016  page 16 : \1\ = PCIE_SMDAT ; \2\ = R_PCA9546_I2C_SDA

(kicad_pcb
	(version 20260206)
	(generator "pcbnew")
	(generator_version "10.0")
	(general
		(thickness 1.6)
		(legacy_teardrops no)
	)
	(paper "A4")
	(title_block
		(title "timecard-production-celestica-r4006 — R4006-B0001-02_R01.brd")
		(comment 1 "Time Appliance Project (Time Card) / footprints 1009-1010 of 1113")
	)
	(layers
		(0 "F.Cu" signal "TOP")
		(4 "In1.Cu" signal "L02_GND1")
		(6 "In2.Cu" signal "L03_SIG1")
		(8 "In3.Cu" signal "L04_GND2")
		(10 "In4.Cu" signal "L05_VCC1")
		(12 "In5.Cu" signal "L06_VCC2")
		(14 "In6.Cu" signal "L07_GND3")
		(16 "In7.Cu" signal "L08_SIG2")
		(18 "In8.Cu" signal "L09_GND4")
		(2 "B.Cu" signal "BOTTOM")
		(9 "F.Adhes" user "F.Adhesive")
		(11 "B.Adhes" user "B.Adhesive")
		(13 "F.Paste" user "Package Geometry/Pastemask Top")
		(15 "B.Paste" user "Package Geometry/Pastemask Bottom")
		(5 "F.SilkS" user "Ref Des/Silkscreen Top")
		(7 "B.SilkS" user "Ref Des/Silkscreen Bottom")
		(1 "F.Mask" user "Board Geometry/Soldermask Top")
		(3 "B.Mask" user "Board Geometry/Soldermask Bottom")
		(17 "Dwgs.User" user "User.Drawings")
		(19 "Cmts.User" user "User.Comments")
		(21 "Eco1.User" user "User.Eco1")
		(23 "Eco2.User" user "User.Eco2")
		(25 "Edge.Cuts" user "Board Geometry/Outline")
		(27 "Margin" user)
		(31 "F.CrtYd" user "Package Geometry/Place Bound Top")
		(29 "B.CrtYd" user "Package Geometry/Place Bound Bottom")
		(35 "F.Fab" user "Ref Des/Assembly Top")
		(33 "B.Fab" user "Ref Des/Assembly Bottom")
	)
	(footprint ""
		(layer "B.Cu")
		(at 117.84711 -47.323248 -90)
		(property "Reference" "C202"
			(at -1.698752 -1.88214 270)
			(unlocked yes)
			(layer "B.SilkS")
			(effects
				(font
					(size 0.635 0.4064)
					(thickness 0.1524)
				)
				(justify mirror)
			)
		)
		(property "Value" "VAL*"
			(at 0 3.718306 270)
			(unlocked yes)
			(layer "B.Fab")
			(hide yes)
			(effects
				(font
					(size 0.7874 0.5842)
					(thickness 0.127)
				)
				(justify mirror)
			)
		)
		(property "Tolerance" "TOL*"
			(at 0 4.861306 270)
			(unlocked yes)
			(layer "Cmts.User")
			(hide yes)
			(effects
				(font
					(size 0.7874 0.5842)
					(thickness 0.127)
				)
				(justify mirror)
			)
		)
		(property "User Part Number" "PARTNUM*"
			(at 0 2.575306 270)
			(unlocked yes)
			(layer "Cmts.User")
			(hide yes)
			(effects
				(font
					(size 0.7874 0.5842)
					(thickness 0.127)
				)
				(justify mirror)
			)
		)
		(property "Device Type" "CAPACITOR-G105-0B104-CK,0.1UF,A"
			(at 0 1.432306 270)
			(unlocked yes)
			(layer "B.Fab")
			(hide yes)
			(effects
				(font
					(size 0.7874 0.5842)
					(thickness 0.127)
				)
				(justify mirror)
			)
		)
		(duplicate_pad_numbers_are_jumpers no)
		(fp_line
			(start -0.970026 0.4699)
			(end 0.970026 0.4699)
			(stroke
				(width 0.1)
				(type default)
			)
			(layer "B.SilkS")
		)
		(fp_line
			(start 0.970026 0.4699)
			(end 0.970026 -0.4699)
			(stroke
				(width 0.1)
				(type default)
			)
			(layer "B.SilkS")
		)
		(fp_line
			(start -0.970026 -0.4699)
			(end -0.970026 0.4699)
			(stroke
				(width 0.1)
				(type default)
			)
			(layer "B.SilkS")
		)
		(fp_line
			(start 0.970026 -0.4699)
			(end -0.970026 -0.4699)
			(stroke
				(width 0.1)
				(type default)
			)
			(layer "B.SilkS")
		)
		(fp_poly
			(pts
				(xy 0.970026 0.4699) (xy -0.970026 0.4699) (xy -0.970026 -0.4699) (xy 0.970026 -0.4699)
			)
			(stroke
				(width 0)
				(type default)
			)
			(fill no)
			(layer "B.CrtYd")
		)
		(fp_line
			(start -0.508 0.3048)
			(end 0.508 0.3048)
			(stroke
				(width 0.1)
				(type default)
			)
			(layer "B.Fab")
		)
		(fp_line
			(start 0.508 0.3048)
			(end 0.508 -0.3048)
			(stroke
				(width 0.1)
				(type default)
			)
			(layer "B.Fab")
		)
		(fp_line
			(start -0.508 -0.3048)
			(end -0.508 0.3048)
			(stroke
				(width 0.1)
				(type default)
			)
			(layer "B.Fab")
		)
		(fp_line
			(start 0.508 -0.3048)
			(end -0.508 -0.3048)
			(stroke
				(width 0.1)
				(type default)
			)
			(layer "B.Fab")
		)
		(pad "1" smd circle
			(at 0.500126 0 90)
			(size 0.635 0.635)
			(layers "B.Cu" "B.Mask" "B.Paste")
			(net "XP3R3V_FPGA")
		)
		(pad "2" smd circle
			(at -0.500126 0 90)
			(size 0.635 0.635)
			(layers "B.Cu" "B.Mask" "B.Paste")
			(net "SG")
		)
	)
	(footprint ""
		(layer "B.Cu")
		(at 21.0566 -40.4876)
		(property "Reference" "R26"
			(at -0.381 4.86537 0)
			(unlocked yes)
			(layer "B.SilkS")
			(effects
				(font
					(size 0.7874 0.5842)
					(thickness 0.1524)
				)
				(justify mirror)
			)
		)
		(property "Value" "VAL*"
			(at -0.02032 2.13233 0)
			(unlocked yes)
			(layer "B.Fab")
			(hide yes)
			(effects
				(font
					(size 0.7874 0.5842)
					(thickness 0.1524)
				)
				(justify mirror)
			)
		)
		(property "Tolerance" "TOL*"
			(at -0.044704 3.05435 0)
			(unlocked yes)
			(layer "Cmts.User")
			(hide yes)
			(effects
				(font
					(size 0.7874 0.5842)
					(thickness 0.1524)
				)
				(justify mirror)
			)
		)
		(property "User Part Number" "PARTNUM*"
			(at -0.02032 4.024884 0)
			(unlocked yes)
			(layer "Cmts.User")
			(hide yes)
			(effects
				(font
					(size 0.7874 0.5842)
					(thickness 0.1524)
				)
				(justify mirror)
			)
		)
		(property "Device Type" "RESISTOR-G155-133R0-01,33OHM,1%"
			(at -0.008382 1.210564 0)
			(unlocked yes)
			(layer "B.Fab")
			(hide yes)
			(effects
				(font
					(size 0.7874 0.5842)
					(thickness 0.1524)
				)
				(justify mirror)
			)
		)
		(duplicate_pad_numbers_are_jumpers no)
		(fp_line
			(start -1.143 -0.5588)
			(end 1.143 -0.5588)
			(stroke
				(width 0.1)
				(type default)
			)
			(layer "B.SilkS")
		)
		(fp_line
			(start -1.143 0.5588)
			(end -1.143 -0.5588)
			(stroke
				(width 0.1)
				(type default)
			)
			(layer "B.SilkS")
		)
		(fp_line
			(start 1.143 -0.5588)
			(end 1.143 0.5588)
			(stroke
				(width 0.1)
				(type default)
			)
			(layer "B.SilkS")
		)
		(fp_line
			(start 1.143 0.5588)
			(end -1.143 0.5588)
			(stroke
				(width 0.1)
				(type default)
			)
			(layer "B.SilkS")
		)
		(fp_rect
			(start 1.143 0.5588)
			(end -1.143 -0.5588)
			(stroke
				(width 0)
				(type default)
			)
			(fill no)
			(layer "B.CrtYd")
		)
		(fp_line
			(start -0.508 -0.3048)
			(end 0.508 -0.3048)
			(stroke
				(width 0.1)
				(type default)
			)
			(layer "B.Fab")
		)
		(fp_line
			(start -0.508 0.3048)
			(end -0.508 -0.3048)
			(stroke
				(width 0.1)
				(type default)
			)
			(layer "B.Fab")
		)
		(fp_line
			(start 0.508 -0.3048)
			(end 0.508 0.3048)
			(stroke
				(width 0.1)
				(type default)
			)
			(layer "B.Fab")
		)
		(fp_line
			(start 0.508 0.3048)
			(end -0.508 0.3048)
			(stroke
				(width 0.1)
				(type default)
			)
			(layer "B.Fab")
		)
		(pad "1" smd rect
			(at 0.5334 0 180)
			(size 0.7112 0.6096)
			(layers "B.Cu" "B.Mask" "B.Paste")
			(net "PCIE_SMDAT")
		)
		(pad "2" smd rect
			(at -0.5334 0 180)
			(size 0.7112 0.6096)
			(layers "B.Cu" "B.Mask" "B.Paste")
			(net "R_PCA9546_I2C_SDA")
		)
		(zone
			(layer "B.Cu")
			(hatch none 0.5)
			(connect_pads
				(clearance 0)
			)
			(min_thickness 0.25)
			(keepout
				(tracks allowed)
				(vias not_allowed)
				(pads allowed)
				(copperpour not_allowed)
				(footprints allowed)
			)
			(placement
				(enabled no)
				(sheetname "")
			)
			(fill
				(thermal_gap 0.5)
				(thermal_bridge_width 0.5)
				(island_removal_mode 0)
			)
			(polygon
				(pts
					(xy 21.1328 -40.1828) (xy 21.1328 -40.7924) (xy 20.9804 -40.7924) (xy 20.9804 -40.1828)
				)
			)
		)
	)
)
